# T6G (Grand Teton) — schematic netlist excerpt (pin names and nets, part order shuffled) for the footprints in the layout excerpt that follows; sources: Cadence DE-HDL packaged netlist, KiCad conversion of 04192023_DAF0TMB3IC0_F0TG_MB_C_brd_V02_OCP.brd

R6118  Q_RES  0 5% CHIP  pkg 0402LF  page 85 : A = PWRGD_P5V_AUX_R3 ; B = PWRGD_P5V_AUX_R2
PR6531  Q_RES  0 5% CHIP  pkg 0402LF  page 362 : A = P0V9_RETIMER_CPU0_SENSE_SH_P ; B = P0V9_RETIMER_CPU0_SENSE_R_P

(kicad_pcb
	(version 20260206)
	(generator "pcbnew")
	(generator_version "10.0")
	(general
		(thickness 1.6)
		(legacy_teardrops no)
	)
	(paper "A4")
	(title_block
		(title "04192023_DAF0TMB3IC0_F0TG_MB_C_brd_V02_OCP.brd")
		(comment 1 "Grand Teton / footprints 3201-3202 of 8354")
	)
	(layers
		(0 "F.Cu" signal "TOP")
		(4 "In1.Cu" signal "GND")
		(6 "In2.Cu" signal "IN1")
		(8 "In3.Cu" signal "GND1")
		(10 "In4.Cu" signal "IN2")
		(12 "In5.Cu" signal "GND2")
		(14 "In6.Cu" signal "IN3")
		(16 "In7.Cu" signal "GND3")
		(18 "In8.Cu" signal "VCC")
		(20 "In9.Cu" signal "VCC1")
		(22 "In10.Cu" signal "GND4")
		(24 "In11.Cu" signal "IN4")
		(26 "In12.Cu" signal "GND5")
		(28 "In13.Cu" signal "IN5")
		(30 "In14.Cu" signal "GND6")
		(32 "In15.Cu" signal "IN6")
		(34 "In16.Cu" signal "GND7")
		(2 "B.Cu" signal "BOTTOM")
		(9 "F.Adhes" user "F.Adhesive")
		(11 "B.Adhes" user "B.Adhesive")
		(13 "F.Paste" user "Package Geometry/Pastemask Top")
		(15 "B.Paste" user "Package Geometry/Pastemask Bottom")
		(5 "F.SilkS" user "Ref Des/Silkscreen Top")
		(7 "B.SilkS" user "Ref Des/Silkscreen Bottom")
		(1 "F.Mask" user "Board Geometry/Soldermask Top")
		(3 "B.Mask" user "Board Geometry/Soldermask Bottom")
		(17 "Dwgs.User" user "User.Drawings")
		(19 "Cmts.User" user "User.Comments")
		(21 "Eco1.User" user "User.Eco1")
		(23 "Eco2.User" user "User.Eco2")
		(25 "Edge.Cuts" user "Board Geometry/Outline")
		(27 "Margin" user)
		(31 "F.CrtYd" user "Package Geometry/Place Bound Top")
		(29 "B.CrtYd" user "Package Geometry/Place Bound Bottom")
		(35 "F.Fab" user "Ref Des/Assembly Top")
		(33 "B.Fab" user "Ref Des/Assembly Bottom")
	)
	(footprint ""
		(layer "F.Cu")
		(at 208.894426 -106.513376)
		(property "Reference" "R6118"
			(at 0 0 0)
			(layer "F.SilkS")
			(hide yes)
			(effects
				(font
					(size 1.27 1.27)
				)
			)
		)
		(property "Value" ""
			(at 0 0 0)
			(layer "F.Fab")
			(effects
				(font
					(size 1.27 1.27)
				)
			)
		)
		(duplicate_pad_numbers_are_jumpers no)
		(fp_line
			(start -0.7874 -0.4064)
			(end 0.7874 -0.4064)
			(stroke
				(width 0.1524)
				(type default)
			)
			(layer "F.SilkS")
		)
		(fp_line
			(start -0.7874 0.4064)
			(end -0.7874 -0.4064)
			(stroke
				(width 0.1524)
				(type default)
			)
			(layer "F.SilkS")
		)
		(fp_line
			(start 0.7874 -0.4064)
			(end 0.7874 0.4064)
			(stroke
				(width 0.1524)
				(type default)
			)
			(layer "F.SilkS")
		)
		(fp_line
			(start 0.7874 0.4064)
			(end -0.7874 0.4064)
			(stroke
				(width 0.1524)
				(type default)
			)
			(layer "F.SilkS")
		)
		(fp_line
			(start -0.67945 -0.305054)
			(end -0.12065 -0.305054)
			(stroke
				(width 0.1)
				(type default)
			)
			(layer "F.Fab")
		)
		(fp_line
			(start -0.67945 0.3048)
			(end -0.67945 -0.305054)
			(stroke
				(width 0.1)
				(type default)
			)
			(layer "F.Fab")
		)
		(fp_line
			(start -0.12065 -0.305054)
			(end -0.12065 -0.2794)
			(stroke
				(width 0.1)
				(type default)
			)
			(layer "F.Fab")
		)
		(fp_line
			(start -0.12065 -0.2794)
			(end 0.12065 -0.2794)
			(stroke
				(width 0.1)
				(type default)
			)
			(layer "F.Fab")
		)
		(fp_line
			(start -0.12065 0.2794)
			(end -0.12065 0.3048)
			(stroke
				(width 0.1)
				(type default)
			)
			(layer "F.Fab")
		)
		(fp_line
			(start -0.12065 0.3048)
			(end -0.67945 0.3048)
			(stroke
				(width 0.1)
				(type default)
			)
			(layer "F.Fab")
		)
		(fp_line
			(start 0.120396 0.2794)
			(end -0.12065 0.2794)
			(stroke
				(width 0.1)
				(type default)
			)
			(layer "F.Fab")
		)
		(fp_line
			(start 0.120396 0.3048)
			(end 0.120396 0.2794)
			(stroke
				(width 0.1)
				(type default)
			)
			(layer "F.Fab")
		)
		(fp_line
			(start 0.12065 -0.3048)
			(end 0.67945 -0.3048)
			(stroke
				(width 0.1)
				(type default)
			)
			(layer "F.Fab")
		)
		(fp_line
			(start 0.12065 -0.2794)
			(end 0.12065 -0.3048)
			(stroke
				(width 0.1)
				(type default)
			)
			(layer "F.Fab")
		)
		(fp_line
			(start 0.67945 -0.3048)
			(end 0.67945 0.3048)
			(stroke
				(width 0.1)
				(type default)
			)
			(layer "F.Fab")
		)
		(fp_line
			(start 0.67945 0.3048)
			(end 0.120396 0.3048)
			(stroke
				(width 0.1)
				(type default)
			)
			(layer "F.Fab")
		)
		(pad "1" smd circle
			(at -0.40005 0)
			(size 0 0)
			(layers "F.Cu" "F.Mask" "F.Paste")
			(net "PWRGD_P5V_AUX_R3")
		)
		(pad "2" smd circle
			(at 0.40005 0)
			(size 0 0)
			(layers "F.Cu" "F.Mask" "F.Paste")
			(net "PWRGD_P5V_AUX_R2")
		)
	)
	(footprint ""
		(layer "F.Cu")
		(at 441.179966 -418.961824)
		(property "Reference" "PR6531"
			(at 0 0 0)
			(layer "F.SilkS")
			(hide yes)
			(effects
				(font
					(size 1.27 1.27)
				)
			)
		)
		(property "Value" ""
			(at 0 0 0)
			(layer "F.Fab")
			(effects
				(font
					(size 1.27 1.27)
				)
			)
		)
		(duplicate_pad_numbers_are_jumpers no)
		(fp_line
			(start -0.7874 -0.4064)
			(end 0.7874 -0.4064)
			(stroke
				(width 0.1524)
				(type default)
			)
			(layer "F.SilkS")
		)
		(fp_line
			(start -0.7874 0.4064)
			(end -0.7874 -0.4064)
			(stroke
				(width 0.1524)
				(type default)
			)
			(layer "F.SilkS")
		)
		(fp_line
			(start 0.7874 -0.4064)
			(end 0.7874 0.4064)
			(stroke
				(width 0.1524)
				(type default)
			)
			(layer "F.SilkS")
		)
		(fp_line
			(start 0.7874 0.4064)
			(end -0.7874 0.4064)
			(stroke
				(width 0.1524)
				(type default)
			)
			(layer "F.SilkS")
		)
		(fp_line
			(start -0.67945 -0.305054)
			(end -0.12065 -0.305054)
			(stroke
				(width 0.1)
				(type default)
			)
			(layer "F.Fab")
		)
		(fp_line
			(start -0.67945 0.3048)
			(end -0.67945 -0.305054)
			(stroke
				(width 0.1)
				(type default)
			)
			(layer "F.Fab")
		)
		(fp_line
			(start -0.12065 -0.305054)
			(end -0.12065 -0.2794)
			(stroke
				(width 0.1)
				(type default)
			)
			(layer "F.Fab")
		)
		(fp_line
			(start -0.12065 -0.2794)
			(end 0.12065 -0.2794)
			(stroke
				(width 0.1)
				(type default)
			)
			(layer "F.Fab")
		)
		(fp_line
			(start -0.12065 0.2794)
			(end -0.12065 0.3048)
			(stroke
				(width 0.1)
				(type default)
			)
			(layer "F.Fab")
		)
		(fp_line
			(start -0.12065 0.3048)
			(end -0.67945 0.3048)
			(stroke
				(width 0.1)
				(type default)
			)
			(layer "F.Fab")
		)
		(fp_line
			(start 0.120396 0.2794)
			(end -0.12065 0.2794)
			(stroke
				(width 0.1)
				(type default)
			)
			(layer "F.Fab")
		)
		(fp_line
			(start 0.120396 0.3048)
			(end 0.120396 0.2794)
			(stroke
				(width 0.1)
				(type default)
			)
			(layer "F.Fab")
		)
		(fp_line
			(start 0.12065 -0.3048)
			(end 0.67945 -0.3048)
			(stroke
				(width 0.1)
				(type default)
			)
			(layer "F.Fab")
		)
		(fp_line
			(start 0.12065 -0.2794)
			(end 0.12065 -0.3048)
			(stroke
				(width 0.1)
				(type default)
			)
			(layer "F.Fab")
		)
		(fp_line
			(start 0.67945 -0.3048)
			(end 0.67945 0.3048)
			(stroke
				(width 0.1)
				(type default)
			)
			(layer "F.Fab")
		)
		(fp_line
			(start 0.67945 0.3048)
			(end 0.120396 0.3048)
			(stroke
				(width 0.1)
				(type default)
			)
			(layer "F.Fab")
		)
		(pad "1" smd circle
			(at -0.40005 0)
			(size 0 0)
			(layers "F.Cu" "F.Mask" "F.Paste")
			(net "P0V9_RETIMER_CPU0_SENSE_SH_P")
		)
		(pad "2" smd circle
			(at 0.40005 0)
			(size 0 0)
			(layers "F.Cu" "F.Mask" "F.Paste")
			(net "P0V9_RETIMER_CPU0_SENSE_R_P")
		)
	)
)
